# BASEBOARD_FAB2 (Tioga Pass) — schematic netlist excerpt (pin names and nets, part order shuffled) for the footprints in the layout excerpt that follows; sources: Cadence DE-HDL packaged netlist, KiCad conversion of Wiwynn_Tioga_Pass_MB.brd

R8F7  RES  33.2 1% CHIP  pkg 0402  page 153 : A = SPI_SWITCH_CLK ; B = SPI_CLK_R1
R1U54  RES  0.0 5% CHIP  pkg 0402  page 152 : A = H_CPU1_MEMGHJ_MEMHOT_LVT3_N ; B = H_CPU1_MEMGHJ_MEMHOT_LVT3_BMC_N
C3M8  CAP  10UF 16V 10% X6S  pkg 0805  page 232 : A = VR_FET_SW_P12V_STBY_PVPP_DEF ; B = GND

(kicad_pcb
	(version 20260206)
	(generator "pcbnew")
	(generator_version "10.0")
	(general
		(thickness 1.6)
		(legacy_teardrops no)
	)
	(paper "A4")
	(title_block
		(title "Wiwynn_Tioga_Pass_MB.brd")
		(comment 1 "Tioga Pass / footprints 3102-3104 of 4770")
	)
	(layers
		(0 "F.Cu" signal "TOP")
		(4 "In1.Cu" signal "L2GND")
		(6 "In2.Cu" signal "L3")
		(8 "In3.Cu" signal "L4GND")
		(10 "In4.Cu" signal "L5")
		(12 "In5.Cu" signal "L6GND")
		(14 "In6.Cu" signal "L7VCC")
		(16 "In7.Cu" signal "L8VCC")
		(18 "In8.Cu" signal "L9GND")
		(20 "In9.Cu" signal "L10")
		(22 "In10.Cu" signal "L11GND")
		(24 "In11.Cu" signal "L12")
		(26 "In12.Cu" signal "L13GND")
		(2 "B.Cu" signal "BOTTOM")
		(9 "F.Adhes" user "F.Adhesive")
		(11 "B.Adhes" user "B.Adhesive")
		(13 "F.Paste" user "Package Geometry/Pastemask Top")
		(15 "B.Paste" user "Package Geometry/Pastemask Bottom")
		(5 "F.SilkS" user "Ref Des/Silkscreen Top")
		(7 "B.SilkS" user "Ref Des/Silkscreen Bottom")
		(1 "F.Mask" user "Board Geometry/Soldermask Top")
		(3 "B.Mask" user "Board Geometry/Soldermask Bottom")
		(17 "Dwgs.User" user "User.Drawings")
		(19 "Cmts.User" user "User.Comments")
		(21 "Eco1.User" user "User.Eco1")
		(23 "Eco2.User" user "User.Eco2")
		(25 "Edge.Cuts" user "Board Geometry/Outline")
		(27 "Margin" user)
		(31 "F.CrtYd" user "Package Geometry/Place Bound Top")
		(29 "B.CrtYd" user "Package Geometry/Place Bound Bottom")
		(35 "F.Fab" user "Ref Des/Assembly Top")
		(33 "B.Fab" user "Ref Des/Assembly Bottom")
	)
	(footprint ""
		(layer "B.Cu")
		(at 425.8056 -16.764 180)
		(property "Reference" "R1U54"
			(at 0 0 0)
			(layer "B.SilkS")
			(hide yes)
			(effects
				(font
					(size 1.27 1.27)
				)
				(justify mirror)
			)
		)
		(property "Value" ""
			(at 0 0 0)
			(layer "B.Fab")
			(effects
				(font
					(size 1.27 1.27)
				)
				(justify mirror)
			)
		)
		(duplicate_pad_numbers_are_jumpers no)
		(fp_poly
			(pts
				(xy 0.2794 -0.1016) (xy -0.2794 -0.1016) (xy -0.2794 0.9906) (xy 0.2794 0.9906)
			)
			(stroke
				(width 0)
				(type default)
			)
			(fill no)
			(layer "B.CrtYd")
		)
		(fp_line
			(start 0.2794 0.9906)
			(end -0.2794 0.9906)
			(stroke
				(width 0.1)
				(type default)
			)
			(layer "B.Fab")
		)
		(fp_line
			(start 0.2794 -0.1016)
			(end 0.2794 0.9906)
			(stroke
				(width 0.1)
				(type default)
			)
			(layer "B.Fab")
		)
		(fp_line
			(start -0.2794 0.9906)
			(end -0.2794 -0.1016)
			(stroke
				(width 0.1)
				(type default)
			)
			(layer "B.Fab")
		)
		(fp_line
			(start -0.2794 -0.1016)
			(end 0.2794 -0.1016)
			(stroke
				(width 0.1)
				(type default)
			)
			(layer "B.Fab")
		)
		(pad "1" smd rect
			(at 0 0)
			(size 0.508 0.508)
			(layers "B.Cu" "B.Mask" "B.Paste")
			(net "H_CPU1_MEMGHJ_MEMHOT_LVT3_N")
		)
		(pad "2" smd rect
			(at 0 0.889)
			(size 0.508 0.508)
			(layers "B.Cu" "B.Mask" "B.Paste")
			(net "H_CPU1_MEMGHJ_MEMHOT_LVT3_BMC_N")
		)
		(zone
			(layer "B.Cu")
			(hatch none 0.5)
			(connect_pads
				(clearance 0)
			)
			(min_thickness 0.25)
			(keepout
				(tracks not_allowed)
				(vias allowed)
				(pads allowed)
				(copperpour not_allowed)
				(footprints allowed)
			)
			(placement
				(enabled no)
				(sheetname "")
			)
			(fill
				(thermal_gap 0.5)
				(thermal_bridge_width 0.5)
				(island_removal_mode 0)
			)
			(polygon
				(pts
					(xy 425.5516 -17.399) (xy 426.0596 -17.399) (xy 426.0596 -17.018) (xy 425.5516 -17.018)
				)
			)
		)
		(zone
			(layer "B.Cu")
			(hatch none 0.5)
			(connect_pads
				(clearance 0)
			)
			(min_thickness 0.25)
			(keepout
				(tracks allowed)
				(vias not_allowed)
				(pads allowed)
				(copperpour not_allowed)
				(footprints allowed)
			)
			(placement
				(enabled no)
				(sheetname "")
			)
			(fill
				(thermal_gap 0.5)
				(thermal_bridge_width 0.5)
				(island_removal_mode 0)
			)
			(polygon
				(pts
					(xy 425.5516 -17.018) (xy 426.0596 -17.018) (xy 426.0596 -17.399) (xy 425.5516 -17.399)
				)
			)
		)
	)
	(footprint ""
		(layer "B.Cu")
		(at 349.631 -133.223 180)
		(property "Reference" "C3M8"
			(at 0 0 0)
			(layer "B.SilkS")
			(hide yes)
			(effects
				(font
					(size 1.27 1.27)
				)
				(justify mirror)
			)
		)
		(property "Value" ""
			(at 0 0 0)
			(layer "B.Fab")
			(effects
				(font
					(size 1.27 1.27)
				)
				(justify mirror)
			)
		)
		(duplicate_pad_numbers_are_jumpers no)
		(fp_poly
			(pts
				(xy 0.7239 -0.2159) (xy -0.7239 -0.2159) (xy -0.7239 1.9939) (xy 0.7239 1.9939)
			)
			(stroke
				(width 0)
				(type default)
			)
			(fill no)
			(layer "B.CrtYd")
		)
		(fp_line
			(start 0.7239 1.9939)
			(end -0.7239 1.9939)
			(stroke
				(width 0.1)
				(type default)
			)
			(layer "B.Fab")
		)
		(fp_line
			(start 0.7239 -0.2159)
			(end 0.7239 1.9939)
			(stroke
				(width 0.1)
				(type default)
			)
			(layer "B.Fab")
		)
		(fp_line
			(start -0.7239 1.9939)
			(end -0.7239 -0.2159)
			(stroke
				(width 0.1)
				(type default)
			)
			(layer "B.Fab")
		)
		(fp_line
			(start -0.7239 -0.2159)
			(end 0.7239 -0.2159)
			(stroke
				(width 0.1)
				(type default)
			)
			(layer "B.Fab")
		)
		(pad "1" smd rect
			(at 0 0)
			(size 1.27 1.016)
			(layers "B.Cu" "B.Mask" "B.Paste")
			(net "VR_FET_SW_P12V_STBY_PVPP_DEF")
		)
		(pad "2" smd rect
			(at 0 1.778)
			(size 1.27 1.016)
			(layers "B.Cu" "B.Mask" "B.Paste")
			(net "GND")
		)
		(zone
			(layer "B.Cu")
			(hatch none 0.5)
			(connect_pads
				(clearance 0)
			)
			(min_thickness 0.25)
			(keepout
				(tracks not_allowed)
				(vias allowed)
				(pads allowed)
				(copperpour not_allowed)
				(footprints allowed)
			)
			(placement
				(enabled no)
				(sheetname "")
			)
			(fill
				(thermal_gap 0.5)
				(thermal_bridge_width 0.5)
				(island_removal_mode 0)
			)
			(polygon
				(pts
					(xy 348.996 -133.731) (xy 350.266 -133.731) (xy 350.266 -134.493) (xy 348.996 -134.493)
				)
			)
		)
	)
	(footprint ""
		(layer "B.Cu")
		(at 387.457188 -57.81675 90)
		(property "Reference" "R8F7"
			(at 0 0 90)
			(layer "B.SilkS")
			(hide yes)
			(effects
				(font
					(size 1.27 1.27)
				)
				(justify mirror)
			)
		)
		(property "Value" ""
			(at 0 0 90)
			(layer "B.Fab")
			(effects
				(font
					(size 1.27 1.27)
				)
				(justify mirror)
			)
		)
		(duplicate_pad_numbers_are_jumpers no)
		(fp_poly
			(pts
				(xy 0.2794 -0.1016) (xy -0.2794 -0.1016) (xy -0.2794 0.9906) (xy 0.2794 0.9906)
			)
			(stroke
				(width 0)
				(type default)
			)
			(fill no)
			(layer "B.CrtYd")
		)
		(fp_line
			(start 0.2794 -0.1016)
			(end 0.2794 0.9906)
			(stroke
				(width 0.1)
				(type default)
			)
			(layer "B.Fab")
		)
		(fp_line
			(start -0.2794 -0.1016)
			(end 0.2794 -0.1016)
			(stroke
				(width 0.1)
				(type default)
			)
			(layer "B.Fab")
		)
		(fp_line
			(start 0.2794 0.9906)
			(end -0.2794 0.9906)
			(stroke
				(width 0.1)
				(type default)
			)
			(layer "B.Fab")
		)
		(fp_line
			(start -0.2794 0.9906)
			(end -0.2794 -0.1016)
			(stroke
				(width 0.1)
				(type default)
			)
			(layer "B.Fab")
		)
		(pad "1" smd rect
			(at 0 0 270)
			(size 0.508 0.508)
			(layers "B.Cu" "B.Mask" "B.Paste")
			(net "SPI_SWITCH_CLK")
		)
		(pad "2" smd rect
			(at 0 0.889 270)
			(size 0.508 0.508)
			(layers "B.Cu" "B.Mask" "B.Paste")
			(net "SPI_CLK_R1")
		)
		(zone
			(layer "B.Cu")
			(hatch none 0.5)
			(connect_pads
				(clearance 0)
			)
			(min_thickness 0.25)
			(keepout
				(tracks allowed)
				(vias not_allowed)
				(pads allowed)
				(copperpour not_allowed)
				(footprints allowed)
			)
			(placement
				(enabled no)
				(sheetname "")
			)
			(fill
				(thermal_gap 0.5)
				(thermal_bridge_width 0.5)
				(island_removal_mode 0)
			)
			(polygon
				(pts
					(xy 387.711188 -58.07075) (xy 387.711188 -57.56275) (xy 388.092188 -57.56275) (xy 388.092188 -58.07075)
				)
			)
		)
		(zone
			(layer "B.Cu")
			(hatch none 0.5)
			(connect_pads
				(clearance 0)
			)
			(min_thickness 0.25)
			(keepout
				(tracks not_allowed)
				(vias allowed)
				(pads allowed)
				(copperpour not_allowed)
				(footprints allowed)
			)
			(placement
				(enabled no)
				(sheetname "")
			)
			(fill
				(thermal_gap 0.5)
				(thermal_bridge_width 0.5)
				(island_removal_mode 0)
			)
			(polygon
				(pts
					(xy 388.092188 -58.07075) (xy 388.092188 -57.56275) (xy 387.711188 -57.56275) (xy 387.711188 -58.07075)
				)
			)
		)
	)
)
